(kicad_pcb
	(version 20260206)
	(generator "pcbnew")
	(generator_version "10.0")
	(general
		(thickness 1.6)
		(legacy_teardrops no)
	)
	(paper "A4")
	(title_block
		(title "Bryce Canyon_F.DPB_16315-1-OCP.brd")
		(comment 1 "Bryce Canyon / footprints 1748-1752 of 2223")
	)
	(layers
		(0 "F.Cu" signal "TOP")
		(4 "In1.Cu" signal "L2GND")
		(6 "In2.Cu" signal "L3")
		(8 "In3.Cu" signal "L4GND")
		(10 "In4.Cu" signal "L5")
		(12 "In5.Cu" signal "L6VCC")
		(14 "In6.Cu" signal "L7VCC")
		(16 "In7.Cu" signal "L8")
		(18 "In8.Cu" signal "L9GND")
		(20 "In9.Cu" signal "L10")
		(22 "In10.Cu" signal "L11GND")
		(2 "B.Cu" signal "BOTTOM")
		(9 "F.Adhes" user "F.Adhesive")
		(11 "B.Adhes" user "B.Adhesive")
		(13 "F.Paste" user "Package Geometry/Pastemask Top")
		(15 "B.Paste" user "Package Geometry/Pastemask Bottom")
		(5 "F.SilkS" user "Ref Des/Silkscreen Top")
		(7 "B.SilkS" user "Ref Des/Silkscreen Bottom")
		(1 "F.Mask" user "Board Geometry/Soldermask Top")
		(3 "B.Mask" user "Board Geometry/Soldermask Bottom")
		(17 "Dwgs.User" user "User.Drawings")
		(19 "Cmts.User" user "User.Comments")
		(21 "Eco1.User" user "User.Eco1")
		(23 "Eco2.User" user "User.Eco2")
		(25 "Edge.Cuts" user "Board Geometry/Outline")
		(27 "Margin" user)
		(31 "F.CrtYd" user "Package Geometry/Place Bound Top")
		(29 "B.CrtYd" user "Package Geometry/Place Bound Bottom")
		(35 "F.Fab" user "Ref Des/Assembly Top")
		(33 "B.Fab" user "Ref Des/Assembly Bottom")
	)
	(footprint ""
		(layer "F.Cu")
		(at 81.002886 -31.405322 180)
		(property "Reference" "R56"
			(at 0 0 180)
			(layer "F.SilkS")
			(hide yes)
			(effects
				(font
					(size 1.27 1.27)
				)
			)
		)
		(property "Value" "0R2J-2-GP"
			(at 0.064008 -3.993896 180)
			(unlocked yes)
			(layer "F.Fab")
			(hide yes)
			(effects
				(font
					(size 1.016 1.016)
					(thickness 0.1524)
				)
			)
		)
		(property "Device Type" "R402H16"
			(at 0.064008 -5.517896 180)
			(unlocked yes)
			(layer "F.Fab")
			(hide yes)
			(effects
				(font
					(size 1.016 1.016)
					(thickness 0.1524)
				)
			)
		)
		(duplicate_pad_numbers_are_jumpers no)
		(fp_line
			(start 0.508 -0.9398)
			(end -0.508 -0.9398)
			(stroke
				(width 0.1524)
				(type default)
			)
			(layer "F.SilkS")
		)
		(fp_line
			(start -0.508 -0.9398)
			(end -0.508 0.9398)
			(stroke
				(width 0.1524)
				(type default)
			)
			(layer "F.SilkS")
		)
		(fp_rect
			(start -0.508 0.9398)
			(end 0.508 -0.9398)
			(stroke
				(width 0)
				(type default)
			)
			(fill no)
			(layer "F.CrtYd")
		)
		(fp_rect
			(start -0.508 0.9398)
			(end 0.508 -0.9398)
			(stroke
				(width 0)
				(type default)
			)
			(fill no)
			(layer "F.Fab")
		)
		(pad "1" smd custom
			(at 0 -0.4445 180)
			(size 0.1397 0.1397)
			(layers "F.Cu" "F.Mask" "F.Paste")
			(net "IO_EXP10_SDA")
			(options
				(clearance outline)
				(anchor circle)
			)
			(primitives
				(gr_poly
					(pts
						(arc
							(start -0.1778 -0.2794)
							(mid -0.249642 -0.249642)
							(end -0.2794 -0.1778)
						)
						(arc
							(start -0.2794 0.1778)
							(mid -0.249642 0.249642)
							(end -0.1778 0.2794)
						)
						(arc
							(start 0.1778 0.2794)
							(mid 0.249642 0.249642)
							(end 0.2794 0.1778)
						)
						(arc
							(start 0.2794 -0.1778)
							(mid 0.249642 -0.249642)
							(end 0.1778 -0.2794)
						)
					)
					(width 0)
					(fill yes)
				)
			)
		)
		(pad "2" smd custom
			(at 0 0.4445 180)
			(size 0.1397 0.1397)
			(layers "F.Cu" "F.Mask" "F.Paste")
			(net "I2C_BMC_A_MISC_SDA")
			(options
				(clearance outline)
				(anchor circle)
			)
			(primitives
				(gr_poly
					(pts
						(arc
							(start -0.1778 -0.2794)
							(mid -0.249642 -0.249642)
							(end -0.2794 -0.1778)
						)
						(arc
							(start -0.2794 0.1778)
							(mid -0.249642 0.249642)
							(end -0.1778 0.2794)
						)
						(arc
							(start 0.1778 0.2794)
							(mid 0.249642 0.249642)
							(end 0.2794 0.1778)
						)
						(arc
							(start 0.2794 -0.1778)
							(mid 0.249642 -0.249642)
							(end 0.1778 -0.2794)
						)
					)
					(width 0)
					(fill yes)
				)
			)
		)
	)
	(footprint ""
		(layer "F.Cu")
		(at 47.916846 -159.490918 180)
		(property "Reference" "R445"
			(at 0 0 180)
			(layer "F.SilkS")
			(hide yes)
			(effects
				(font
					(size 1.27 1.27)
				)
			)
		)
		(property "Value" "200KR2F-L-GP"
			(at 0.064008 -3.993896 180)
			(unlocked yes)
			(layer "F.Fab")
			(hide yes)
			(effects
				(font
					(size 1.016 1.016)
					(thickness 0.1524)
				)
			)
		)
		(property "Device Type" "R402H16"
			(at 0.064008 -5.517896 180)
			(unlocked yes)
			(layer "F.Fab")
			(hide yes)
			(effects
				(font
					(size 1.016 1.016)
					(thickness 0.1524)
				)
			)
		)
		(duplicate_pad_numbers_are_jumpers no)
		(fp_line
			(start 0.508 -0.9398)
			(end -0.508 -0.9398)
			(stroke
				(width 0.1524)
				(type default)
			)
			(layer "F.SilkS")
		)
		(fp_line
			(start -0.508 -0.9398)
			(end -0.508 0.9398)
			(stroke
				(width 0.1524)
				(type default)
			)
			(layer "F.SilkS")
		)
		(fp_rect
			(start -0.508 0.9398)
			(end 0.508 -0.9398)
			(stroke
				(width 0)
				(type default)
			)
			(fill no)
			(layer "F.CrtYd")
		)
		(fp_rect
			(start -0.508 0.9398)
			(end 0.508 -0.9398)
			(stroke
				(width 0)
				(type default)
			)
			(fill no)
			(layer "F.Fab")
		)
		(pad "1" smd custom
			(at 0 -0.4445 180)
			(size 0.1397 0.1397)
			(layers "F.Cu" "F.Mask" "F.Paste")
			(net "SW_HDD_R13")
			(options
				(clearance outline)
				(anchor circle)
			)
			(primitives
				(gr_poly
					(pts
						(arc
							(start -0.1778 -0.2794)
							(mid -0.249642 -0.249642)
							(end -0.2794 -0.1778)
						)
						(arc
							(start -0.2794 0.1778)
							(mid -0.249642 0.249642)
							(end -0.1778 0.2794)
						)
						(arc
							(start 0.1778 0.2794)
							(mid 0.249642 0.249642)
							(end 0.2794 0.1778)
						)
						(arc
							(start 0.2794 -0.1778)
							(mid 0.249642 -0.249642)
							(end 0.1778 -0.2794)
						)
					)
					(width 0)
					(fill yes)
				)
			)
		)
		(pad "2" smd custom
			(at 0 0.4445 180)
			(size 0.1397 0.1397)
			(layers "F.Cu" "F.Mask" "F.Paste")
			(net "SW_HDD_N13")
			(options
				(clearance outline)
				(anchor circle)
			)
			(primitives
				(gr_poly
					(pts
						(arc
							(start -0.1778 -0.2794)
							(mid -0.249642 -0.249642)
							(end -0.2794 -0.1778)
						)
						(arc
							(start -0.2794 0.1778)
							(mid -0.249642 0.249642)
							(end -0.1778 0.2794)
						)
						(arc
							(start 0.1778 0.2794)
							(mid 0.249642 0.249642)
							(end 0.2794 0.1778)
						)
						(arc
							(start 0.2794 -0.1778)
							(mid 0.249642 -0.249642)
							(end 0.1778 -0.2794)
						)
					)
					(width 0)
					(fill yes)
				)
			)
		)
	)
	(footprint ""
		(layer "F.Cu")
		(at 264.301732 19.287744 90)
		(property "Reference" "R137"
			(at 0 0 90)
			(layer "F.SilkS")
			(hide yes)
			(effects
				(font
					(size 1.27 1.27)
				)
			)
		)
		(property "Value" "4K7R2F-GP"
			(at 0.064008 -3.993896 90)
			(unlocked yes)
			(layer "F.Fab")
			(hide yes)
			(effects
				(font
					(size 1.016 1.016)
					(thickness 0.1524)
				)
			)
		)
		(property "Device Type" "R402H16"
			(at 0.064008 -5.517896 90)
			(unlocked yes)
			(layer "F.Fab")
			(hide yes)
			(effects
				(font
					(size 1.016 1.016)
					(thickness 0.1524)
				)
			)
		)
		(duplicate_pad_numbers_are_jumpers no)
		(fp_line
			(start 0.508 -0.9398)
			(end -0.508 -0.9398)
			(stroke
				(width 0.1524)
				(type default)
			)
			(layer "F.SilkS")
		)
		(fp_line
			(start -0.508 -0.9398)
			(end -0.508 0.9398)
			(stroke
				(width 0.1524)
				(type default)
			)
			(layer "F.SilkS")
		)
		(fp_rect
			(start -0.508 0.9398)
			(end 0.508 -0.9398)
			(stroke
				(width 0)
				(type default)
			)
			(fill no)
			(layer "F.CrtYd")
		)
		(fp_rect
			(start -0.508 0.9398)
			(end 0.508 -0.9398)
			(stroke
				(width 0)
				(type default)
			)
			(fill no)
			(layer "F.Fab")
		)
		(pad "1" smd custom
			(at 0 -0.4445 90)
			(size 0.1397 0.1397)
			(layers "F.Cu" "F.Mask" "F.Paste")
			(net "USB_OCS_N1")
			(options
				(clearance outline)
				(anchor circle)
			)
			(primitives
				(gr_poly
					(pts
						(arc
							(start -0.1778 -0.2794)
							(mid -0.249642 -0.249642)
							(end -0.2794 -0.1778)
						)
						(arc
							(start -0.2794 0.1778)
							(mid -0.249642 0.249642)
							(end -0.1778 0.2794)
						)
						(arc
							(start 0.1778 0.2794)
							(mid 0.249642 0.249642)
							(end 0.2794 0.1778)
						)
						(arc
							(start 0.2794 -0.1778)
							(mid 0.249642 -0.249642)
							(end 0.1778 -0.2794)
						)
					)
					(width 0)
					(fill yes)
				)
			)
		)
		(pad "2" smd custom
			(at 0 0.4445 90)
			(size 0.1397 0.1397)
			(layers "F.Cu" "F.Mask" "F.Paste")
			(net "GND")
			(options
				(clearance outline)
				(anchor circle)
			)
			(primitives
				(gr_poly
					(pts
						(arc
							(start -0.1778 -0.2794)
							(mid -0.249642 -0.249642)
							(end -0.2794 -0.1778)
						)
						(arc
							(start -0.2794 0.1778)
							(mid -0.249642 0.249642)
							(end -0.1778 0.2794)
						)
						(arc
							(start 0.1778 0.2794)
							(mid 0.249642 0.249642)
							(end 0.2794 0.1778)
						)
						(arc
							(start 0.2794 -0.1778)
							(mid 0.249642 -0.249642)
							(end 0.1778 -0.2794)
						)
					)
					(width 0)
					(fill yes)
				)
			)
		)
	)
	(footprint ""
		(layer "F.Cu")
		(at 246.47906 -292.989 -90)
		(property "Reference" "R14"
			(at 0 0 270)
			(layer "F.SilkS")
			(hide yes)
			(effects
				(font
					(size 1.27 1.27)
				)
			)
		)
		(property "Value" "4K7R2J-2-GP"
			(at 0.064008 -3.993896 270)
			(unlocked yes)
			(layer "F.Fab")
			(hide yes)
			(effects
				(font
					(size 1.016 1.016)
					(thickness 0.1524)
				)
			)
		)
		(property "Device Type" "R402H16"
			(at 0.064008 -5.517896 270)
			(unlocked yes)
			(layer "F.Fab")
			(hide yes)
			(effects
				(font
					(size 1.016 1.016)
					(thickness 0.1524)
				)
			)
		)
		(duplicate_pad_numbers_are_jumpers no)
		(fp_line
			(start -0.508 -0.9398)
			(end -0.508 0.9398)
			(stroke
				(width 0.1524)
				(type default)
			)
			(layer "F.SilkS")
		)
		(fp_line
			(start 0.508 -0.9398)
			(end -0.508 -0.9398)
			(stroke
				(width 0.1524)
				(type default)
			)
			(layer "F.SilkS")
		)
		(fp_rect
			(start -0.508 0.9398)
			(end 0.508 -0.9398)
			(stroke
				(width 0)
				(type default)
			)
			(fill no)
			(layer "F.CrtYd")
		)
		(fp_rect
			(start -0.508 0.9398)
			(end 0.508 -0.9398)
			(stroke
				(width 0)
				(type default)
			)
			(fill no)
			(layer "F.Fab")
		)
		(pad "1" smd custom
			(at 0 -0.4445 270)
			(size 0.1397 0.1397)
			(layers "F.Cu" "F.Mask" "F.Paste")
			(net "P3V3_STBY_A")
			(options
				(clearance outline)
				(anchor circle)
			)
			(primitives
				(gr_poly
					(pts
						(arc
							(start -0.1778 -0.2794)
							(mid -0.249642 -0.249642)
							(end -0.2794 -0.1778)
						)
						(arc
							(start -0.2794 0.1778)
							(mid -0.249642 0.249642)
							(end -0.1778 0.2794)
						)
						(arc
							(start 0.1778 0.2794)
							(mid 0.249642 0.249642)
							(end 0.2794 0.1778)
						)
						(arc
							(start 0.2794 -0.1778)
							(mid 0.249642 -0.249642)
							(end 0.1778 -0.2794)
						)
					)
					(width 0)
					(fill yes)
				)
			)
		)
		(pad "2" smd custom
			(at 0 0.4445 270)
			(size 0.1397 0.1397)
			(layers "F.Cu" "F.Mask" "F.Paste")
			(net "BMC_A_TO_EXP_A_RESET_N")
			(options
				(clearance outline)
				(anchor circle)
			)
			(primitives
				(gr_poly
					(pts
						(arc
							(start -0.1778 -0.2794)
							(mid -0.249642 -0.249642)
							(end -0.2794 -0.1778)
						)
						(arc
							(start -0.2794 0.1778)
							(mid -0.249642 0.249642)
							(end -0.1778 0.2794)
						)
						(arc
							(start 0.1778 0.2794)
							(mid 0.249642 0.249642)
							(end 0.2794 0.1778)
						)
						(arc
							(start 0.2794 -0.1778)
							(mid 0.249642 -0.249642)
							(end 0.1778 -0.2794)
						)
					)
					(width 0)
					(fill yes)
				)
			)
		)
	)
	(footprint ""
		(layer "F.Cu")
		(at 259.025644 -390.536938 90)
		(property "Reference" "R1166"
			(at 0 0 90)
			(layer "F.SilkS")
			(hide yes)
			(effects
				(font
					(size 1.27 1.27)
				)
			)
		)
		(property "Value" "D0003R4026F-GP"
			(at -6.737858 -1.79959 90)
			(unlocked yes)
			(layer "F.Fab")
			(hide yes)
			(effects
				(font
					(size 1.016 1.016)
					(thickness 0.1524)
				)
			)
		)
		(property "Device Type" "RL4026-4PH149"
			(at -6.737858 -3.32359 90)
			(unlocked yes)
			(layer "F.Fab")
			(hide yes)
			(effects
				(font
					(size 1.016 1.016)
					(thickness 0.1524)
				)
			)
		)
		(duplicate_pad_numbers_are_jumpers no)
		(fp_line
			(start 5.588 -3.937)
			(end 5.588 3.937)
			(stroke
				(width 0.1524)
				(type default)
			)
			(layer "F.SilkS")
		)
		(fp_line
			(start -5.588 -3.937)
			(end 5.588 -3.937)
			(stroke
				(width 0.1524)
				(type default)
			)
			(layer "F.SilkS")
		)
		(fp_line
			(start -5.6769 2.4765)
			(end -5.6769 4.0259)
			(stroke
				(width 0.3302)
				(type default)
			)
			(layer "F.SilkS")
		)
		(fp_line
			(start 5.588 3.937)
			(end -5.588 3.937)
			(stroke
				(width 0.1524)
				(type default)
			)
			(layer "F.SilkS")
		)
		(fp_line
			(start -5.588 3.937)
			(end -5.588 -3.937)
			(stroke
				(width 0.1524)
				(type default)
			)
			(layer "F.SilkS")
		)
		(fp_line
			(start -5.6769 4.0259)
			(end -4.1402 4.0259)
			(stroke
				(width 0.3302)
				(type default)
			)
			(layer "F.SilkS")
		)
		(fp_poly
			(pts
				(xy -4.703572 3.998468) (xy -5.289804 4.5847) (xy -4.11734 4.5847)
			)
			(stroke
				(width 0)
				(type default)
			)
			(fill yes)
			(layer "F.SilkS")
		)
		(fp_rect
			(start -5.0546 3.302)
			(end 5.0546 -3.302)
			(stroke
				(width 0)
				(type default)
			)
			(fill no)
			(layer "F.CrtYd")
		)
		(fp_poly
			(pts
				(xy -5.842 4.191) (xy -5.842 -4.191) (xy 5.842 -4.191) (xy 5.842 -0.00635) (xy 5.0546 -0.00635)
				(xy 5.0546 -3.302) (xy -5.0546 -3.302) (xy -5.0546 3.302) (xy 5.0546 3.302) (xy 5.0546 0.00635)
				(xy 5.842 0.00635) (xy 5.842 4.191)
			)
			(stroke
				(width 0)
				(type default)
			)
			(fill no)
			(layer "F.CrtYd")
		)
		(fp_rect
			(start -5.842 4.191)
			(end 5.842 -4.191)
			(stroke
				(width 0)
				(type default)
			)
			(fill no)
			(layer "F.Fab")
		)
		(pad "1" smd rect
			(at -4.115054 0.890016 90)
			(size 2.4384 5.588)
			(layers "F.Cu" "F.Mask" "F.Paste")
			(net "MB3_P12V_IN_R")
		)
		(pad "2" smd rect
			(at 4.115054 0.890016 90)
			(size 2.4384 5.588)
			(layers "F.Cu" "F.Mask" "F.Paste")
			(net "P12V_IN")
		)
		(pad "3" smd rect
			(at -4.115054 -3.245104 90)
			(size 2.4384 0.889)
			(layers "F.Cu" "F.Mask" "F.Paste")
			(net "MB3_CM_SENSE_R1_N")
		)
		(pad "4" smd rect
			(at 4.115054 -3.245104 90)
			(size 2.4384 0.889)
			(layers "F.Cu" "F.Mask" "F.Paste")
			(net "MB3_CM_SENSE_R1_P")
		)
		(zone
			(layer "F.Cu")
			(hatch none 0.5)
			(connect_pads
				(clearance 0)
			)
			(min_thickness 0.25)
			(keepout
				(tracks allowed)
				(vias not_allowed)
				(pads allowed)
				(copperpour not_allowed)
				(footprints allowed)
			)
			(placement
				(enabled no)
				(sheetname "")
			)
			(fill
				(thermal_gap 0.5)
				(thermal_bridge_width 0.5)
				(island_removal_mode 0)
			)
			(polygon
				(pts
					(xy 256.22504 -393.432792) (xy 257.12166 -393.432792) (xy 257.12166 -395.871192) (xy 256.22504 -395.871192)
				)
			)
		)
		(zone
			(layer "F.Cu")
			(hatch none 0.5)
			(connect_pads
				(clearance 0)
			)
			(min_thickness 0.25)
			(keepout
				(tracks allowed)
				(vias not_allowed)
				(pads allowed)
				(copperpour not_allowed)
				(footprints allowed)
			)
			(placement
				(enabled no)
				(sheetname "")
			)
			(fill
				(thermal_gap 0.5)
				(thermal_bridge_width 0.5)
				(island_removal_mode 0)
			)
			(polygon
				(pts
					(xy 256.22504 -385.202684) (xy 257.12166 -385.202684) (xy 257.12166 -387.641084) (xy 256.22504 -387.641084)
				)
			)
		)
		(zone
			(layer "F.Cu")
			(hatch none 0.5)
			(connect_pads
				(clearance 0)
			)
			(min_thickness 0.25)
			(keepout
				(tracks not_allowed)
				(vias allowed)
				(pads allowed)
				(copperpour not_allowed)
				(footprints allowed)
			)
			(placement
				(enabled no)
				(sheetname "")
			)
			(fill
				(thermal_gap 0.5)
				(thermal_bridge_width 0.5)
				(island_removal_mode 0)
			)
			(polygon
				(pts
					(xy 257.12166 -393.432792) (xy 257.12166 -395.871192) (xy 256.22504 -395.871192) (xy 256.22504 -393.432792)
				)
			)
		)
		(zone
			(layer "F.Cu")
			(hatch none 0.5)
			(connect_pads
				(clearance 0)
			)
			(min_thickness 0.25)
			(keepout
				(tracks not_allowed)
				(vias allowed)
				(pads allowed)
				(copperpour not_allowed)
				(footprints allowed)
			)
			(placement
				(enabled no)
				(sheetname "")
			)
			(fill
				(thermal_gap 0.5)
				(thermal_bridge_width 0.5)
				(island_removal_mode 0)
			)
			(polygon
				(pts
					(xy 257.12166 -385.202684) (xy 257.12166 -387.641084) (xy 256.22504 -387.641084) (xy 256.22504 -385.202684)
				)
			)
		)
	)
)
